# S9S_MB_2U (Grand Teton) — schematic netlist excerpt (pin names and nets, part order shuffled) for the footprints in the layout excerpt that follows; sources: Cadence DE-HDL packaged netlist, KiCad conversion of 03242023_DA0F0TMBIJ0_F0T_Motherboard_J_brd_V01_OCP.brd

R1408  Q_RES  2K 1% CHIP  pkg 0402LF  page 219 : A = FM_PVCCINFAON_CPU1_R_EN ; B = GND
PC615_P0_1  Q_CAP  22UF 4V 20% X6S  pkg C0805  page 271 : A = PVCCFA_EHV_FIVRA_CPU0 ; B = GND
PC305_P0_1  Q_CAP  22UF 16V 20% X6S  pkg C0805  page 267 : A = SW_P12V_PVCCIN_CPU0_FLT ; B = GND

(kicad_pcb
	(version 20260206)
	(generator "pcbnew")
	(generator_version "10.0")
	(general
		(thickness 1.6)
		(legacy_teardrops no)
	)
	(paper "A4")
	(title_block
		(title "03242023_DA0F0TMBIJ0_F0T_Motherboard_J_brd_V01_OCP.brd")
		(comment 1 "Grand Teton / footprints 6072-6074 of 6105")
	)
	(layers
		(0 "F.Cu" signal "TOP")
		(4 "In1.Cu" signal "GND")
		(6 "In2.Cu" signal "IN1")
		(8 "In3.Cu" signal "GND1")
		(10 "In4.Cu" signal "IN2")
		(12 "In5.Cu" signal "GND2")
		(14 "In6.Cu" signal "IN3")
		(16 "In7.Cu" signal "GND3")
		(18 "In8.Cu" signal "VCC")
		(20 "In9.Cu" signal "VCC1")
		(22 "In10.Cu" signal "GND4")
		(24 "In11.Cu" signal "IN4")
		(26 "In12.Cu" signal "GND5")
		(28 "In13.Cu" signal "IN5")
		(30 "In14.Cu" signal "GND6")
		(32 "In15.Cu" signal "IN6")
		(34 "In16.Cu" signal "GND7")
		(2 "B.Cu" signal "BOTTOM")
		(9 "F.Adhes" user "F.Adhesive")
		(11 "B.Adhes" user "B.Adhesive")
		(13 "F.Paste" user "Package Geometry/Pastemask Top")
		(15 "B.Paste" user "Package Geometry/Pastemask Bottom")
		(5 "F.SilkS" user "Ref Des/Silkscreen Top")
		(7 "B.SilkS" user "Ref Des/Silkscreen Bottom")
		(1 "F.Mask" user "Board Geometry/Soldermask Top")
		(3 "B.Mask" user "Board Geometry/Soldermask Bottom")
		(17 "Dwgs.User" user "User.Drawings")
		(19 "Cmts.User" user "User.Comments")
		(21 "Eco1.User" user "User.Eco1")
		(23 "Eco2.User" user "User.Eco2")
		(25 "Edge.Cuts" user "Board Geometry/Outline")
		(27 "Margin" user)
		(31 "F.CrtYd" user "Package Geometry/Place Bound Top")
		(29 "B.CrtYd" user "Package Geometry/Place Bound Bottom")
		(35 "F.Fab" user "Ref Des/Assembly Top")
		(33 "B.Fab" user "Ref Des/Assembly Bottom")
	)
	(footprint ""
		(layer "B.Cu")
		(at 164.64788 -121.376948)
		(property "Reference" "R1408"
			(at 0 0 0)
			(layer "B.SilkS")
			(hide yes)
			(effects
				(font
					(size 1.27 1.27)
				)
				(justify mirror)
			)
		)
		(property "Value" ""
			(at 0 0 0)
			(layer "B.Fab")
			(effects
				(font
					(size 1.27 1.27)
				)
				(justify mirror)
			)
		)
		(duplicate_pad_numbers_are_jumpers no)
		(fp_line
			(start -0.7874 -0.4064)
			(end -0.7874 0.4064)
			(stroke
				(width 0.1524)
				(type default)
			)
			(layer "B.SilkS")
		)
		(fp_line
			(start -0.7874 0.4064)
			(end 0.7874 0.4064)
			(stroke
				(width 0.1524)
				(type default)
			)
			(layer "B.SilkS")
		)
		(fp_line
			(start 0.7874 -0.4064)
			(end -0.7874 -0.4064)
			(stroke
				(width 0.1524)
				(type default)
			)
			(layer "B.SilkS")
		)
		(fp_line
			(start 0.7874 0.4064)
			(end 0.7874 -0.4064)
			(stroke
				(width 0.1524)
				(type default)
			)
			(layer "B.SilkS")
		)
		(fp_line
			(start -0.67945 -0.3048)
			(end -0.67945 0.3048)
			(stroke
				(width 0.1)
				(type default)
			)
			(layer "B.Fab")
		)
		(fp_line
			(start -0.67945 0.3048)
			(end -0.120396 0.3048)
			(stroke
				(width 0.1)
				(type default)
			)
			(layer "B.Fab")
		)
		(fp_line
			(start -0.12065 -0.3048)
			(end -0.67945 -0.3048)
			(stroke
				(width 0.1)
				(type default)
			)
			(layer "B.Fab")
		)
		(fp_line
			(start -0.12065 -0.2794)
			(end -0.12065 -0.3048)
			(stroke
				(width 0.1)
				(type default)
			)
			(layer "B.Fab")
		)
		(fp_line
			(start -0.120396 0.2794)
			(end 0.12065 0.2794)
			(stroke
				(width 0.1)
				(type default)
			)
			(layer "B.Fab")
		)
		(fp_line
			(start -0.120396 0.3048)
			(end -0.120396 0.2794)
			(stroke
				(width 0.1)
				(type default)
			)
			(layer "B.Fab")
		)
		(fp_line
			(start 0.12065 -0.305054)
			(end 0.12065 -0.2794)
			(stroke
				(width 0.1)
				(type default)
			)
			(layer "B.Fab")
		)
		(fp_line
			(start 0.12065 -0.2794)
			(end -0.12065 -0.2794)
			(stroke
				(width 0.1)
				(type default)
			)
			(layer "B.Fab")
		)
		(fp_line
			(start 0.12065 0.2794)
			(end 0.12065 0.3048)
			(stroke
				(width 0.1)
				(type default)
			)
			(layer "B.Fab")
		)
		(fp_line
			(start 0.12065 0.3048)
			(end 0.67945 0.3048)
			(stroke
				(width 0.1)
				(type default)
			)
			(layer "B.Fab")
		)
		(fp_line
			(start 0.67945 -0.305054)
			(end 0.12065 -0.305054)
			(stroke
				(width 0.1)
				(type default)
			)
			(layer "B.Fab")
		)
		(fp_line
			(start 0.67945 0.3048)
			(end 0.67945 -0.305054)
			(stroke
				(width 0.1)
				(type default)
			)
			(layer "B.Fab")
		)
		(pad "1" smd circle
			(at 0.40005 0 180)
			(size 0 0)
			(layers "B.Cu" "B.Mask" "B.Paste")
			(net "FM_PVCCINFAON_CPU1_R_EN")
		)
		(pad "2" smd circle
			(at -0.40005 0 180)
			(size 0 0)
			(layers "B.Cu" "B.Mask" "B.Paste")
			(net "GND")
		)
	)
	(footprint ""
		(layer "B.Cu")
		(at 412.611316 -353.25939 -90)
		(property "Reference" "PC615_P0_1"
			(at 0 0 90)
			(layer "B.SilkS")
			(hide yes)
			(effects
				(font
					(size 1.27 1.27)
				)
				(justify mirror)
			)
		)
		(property "Value" ""
			(at 0 0 90)
			(layer "B.Fab")
			(effects
				(font
					(size 1.27 1.27)
				)
				(justify mirror)
			)
		)
		(duplicate_pad_numbers_are_jumpers no)
		(fp_line
			(start -1.524 0.762)
			(end 1.524 0.762)
			(stroke
				(width 0.1524)
				(type default)
			)
			(layer "B.SilkS")
		)
		(fp_line
			(start 1.524 0.762)
			(end 1.524 -0.762)
			(stroke
				(width 0.1524)
				(type default)
			)
			(layer "B.SilkS")
		)
		(fp_line
			(start -1.524 -0.762)
			(end -1.524 0.762)
			(stroke
				(width 0.1524)
				(type default)
			)
			(layer "B.SilkS")
		)
		(fp_line
			(start 1.524 -0.762)
			(end -1.524 -0.762)
			(stroke
				(width 0.1524)
				(type default)
			)
			(layer "B.SilkS")
		)
		(fp_line
			(start -1.1049 0.724916)
			(end -1.1049 -0.724916)
			(stroke
				(width 0.1)
				(type default)
			)
			(layer "B.Fab")
		)
		(fp_line
			(start 1.1049 0.724916)
			(end -1.1049 0.724916)
			(stroke
				(width 0.1)
				(type default)
			)
			(layer "B.Fab")
		)
		(fp_line
			(start -1.1049 -0.724916)
			(end 1.1049 -0.724916)
			(stroke
				(width 0.1)
				(type default)
			)
			(layer "B.Fab")
		)
		(fp_line
			(start 1.1049 -0.724916)
			(end 1.1049 0.724916)
			(stroke
				(width 0.1)
				(type default)
			)
			(layer "B.Fab")
		)
		(pad "1" smd rect
			(at 0.889 0 270)
			(size 1.016 1.27)
			(layers "B.Cu" "B.Mask" "B.Paste")
			(net "PVCCFA_EHV_FIVRA_CPU0")
		)
		(pad "2" smd rect
			(at -0.889 0 270)
			(size 1.016 1.27)
			(layers "B.Cu" "B.Mask" "B.Paste")
			(net "GND")
		)
	)
	(footprint ""
		(layer "B.Cu")
		(at 348.13494 -333.639922 90)
		(property "Reference" "PC305_P0_1"
			(at 0 0 90)
			(layer "B.SilkS")
			(hide yes)
			(effects
				(font
					(size 1.27 1.27)
				)
				(justify mirror)
			)
		)
		(property "Value" ""
			(at 0 0 90)
			(layer "B.Fab")
			(effects
				(font
					(size 1.27 1.27)
				)
				(justify mirror)
			)
		)
		(duplicate_pad_numbers_are_jumpers no)
		(fp_line
			(start 1.524 -0.762)
			(end -1.524 -0.762)
			(stroke
				(width 0.1524)
				(type default)
			)
			(layer "B.SilkS")
		)
		(fp_line
			(start -1.524 -0.762)
			(end -1.524 0.762)
			(stroke
				(width 0.1524)
				(type default)
			)
			(layer "B.SilkS")
		)
		(fp_line
			(start 1.524 0.762)
			(end 1.524 -0.762)
			(stroke
				(width 0.1524)
				(type default)
			)
			(layer "B.SilkS")
		)
		(fp_line
			(start -1.524 0.762)
			(end 1.524 0.762)
			(stroke
				(width 0.1524)
				(type default)
			)
			(layer "B.SilkS")
		)
		(fp_line
			(start 1.1049 -0.724916)
			(end 1.1049 0.724916)
			(stroke
				(width 0.1)
				(type default)
			)
			(layer "B.Fab")
		)
		(fp_line
			(start -1.1049 -0.724916)
			(end 1.1049 -0.724916)
			(stroke
				(width 0.1)
				(type default)
			)
			(layer "B.Fab")
		)
		(fp_line
			(start 1.1049 0.724916)
			(end -1.1049 0.724916)
			(stroke
				(width 0.1)
				(type default)
			)
			(layer "B.Fab")
		)
		(fp_line
			(start -1.1049 0.724916)
			(end -1.1049 -0.724916)
			(stroke
				(width 0.1)
				(type default)
			)
			(layer "B.Fab")
		)
		(pad "1" smd rect
			(at 0.889 0 90)
			(size 1.016 1.27)
			(layers "B.Cu" "B.Mask" "B.Paste")
			(net "SW_P12V_PVCCIN_CPU0_FLT")
		)
		(pad "2" smd rect
			(at -0.889 0 90)
			(size 1.016 1.27)
			(layers "B.Cu" "B.Mask" "B.Paste")
			(net "GND")
		)
	)
)
